(kicad_pcb
	(version 20241229)
	(generator "pcbnew")
	(generator_version "9.0")
	(general
		(thickness 1.552)
		(legacy_teardrops no)
	)
	(paper "A4")
	(title_block
		(date "2023-07-25")
		(rev "1.1.4")
		(comment 9 "footprints 81-85 of 379")
	)
	(layers
		(0 "F.Cu" signal)
		(4 "In1.Cu" signal)
		(6 "In2.Cu" signal)
		(8 "In3.Cu" signal)
		(10 "In4.Cu" signal)
		(12 "In5.Cu" signal)
		(14 "In6.Cu" signal)
		(2 "B.Cu" signal)
		(9 "F.Adhes" user "F.Adhesive")
		(11 "B.Adhes" user "B.Adhesive")
		(13 "F.Paste" user)
		(15 "B.Paste" user)
		(5 "F.SilkS" user "F.Silkscreen")
		(7 "B.SilkS" user "B.Silkscreen")
		(1 "F.Mask" user)
		(3 "B.Mask" user)
		(17 "Dwgs.User" user "User.Drawings")
		(19 "Cmts.User" user "User.Comments")
		(21 "Eco1.User" user "User.Eco1")
		(23 "Eco2.User" user "User.Eco2")
		(25 "Edge.Cuts" user)
		(27 "Margin" user)
		(31 "F.CrtYd" user "F.Courtyard")
		(29 "B.CrtYd" user "B.Courtyard")
		(35 "F.Fab" user)
		(33 "B.Fab" user)
	)
	(footprint "antmicro-footprints:L_0402_1005Metric"
		(layer "F.Cu")
		(at 85.2 104.15)
		(descr "Inductor SMD 0402")
		(tags "Inductor SMD 0402")
		(property "Reference" "L5"
			(at 2.43 -7.91 0)
			(layer "F.SilkS")
			(effects
				(font
					(size 0.65 0.65)
					(thickness 0.15)
				)
				(justify left bottom)
			)
		)
		(property "Value" "L_6n2_0.7A_0402"
			(at 0 1.4 0)
			(layer "F.Fab")
			(hide yes)
			(effects
				(font
					(size 0.7 0.7)
					(thickness 0.15)
				)
				(justify left bottom)
			)
		)
		(property "Datasheet" "https://www.mouser.com/datasheet/2/281/1/JELF243A_0050-1380872.pdf"
			(at 0 0 0)
			(layer "F.Fab")
			(hide yes)
			(effects
				(font
					(size 1.27 1.27)
					(thickness 0.15)
				)
			)
		)
		(property "Description" "Wirewound Inductor, 6.2 nH, 0.09 ohm, 8 GHz, 700 mA, 0402 [1005 Metric], LQW"
			(at 0 0 0)
			(layer "F.Fab")
			(hide yes)
			(effects
				(font
					(size 1.27 1.27)
					(thickness 0.15)
				)
			)
		)
		(property "Author" "Antmicro"
			(at 0 0 0)
			(layer "F.Fab")
			(hide yes)
			(effects
				(font
					(size 1 1)
					(thickness 0.15)
				)
			)
		)
		(property "IMax" "0.7 A"
			(at 0 0 0)
			(layer "F.Fab")
			(hide yes)
			(effects
				(font
					(size 1 1)
					(thickness 0.15)
				)
			)
		)
		(property "ISat" ""
			(at 0 0 0)
			(layer "F.Fab")
			(hide yes)
			(effects
				(font
					(size 1 1)
					(thickness 0.15)
				)
			)
		)
		(property "License" "Apache-2.0"
			(at 0 0 0)
			(layer "F.Fab")
			(hide yes)
			(effects
				(font
					(size 1 1)
					(thickness 0.15)
				)
			)
		)
		(property "MPN" "LQW15AN6N2C00D"
			(at 0 0 0)
			(layer "F.Fab")
			(hide yes)
			(effects
				(font
					(size 1 1)
					(thickness 0.15)
				)
			)
		)
		(property "Manufacturer" "Murata"
			(at 0 0 0)
			(layer "F.Fab")
			(hide yes)
			(effects
				(font
					(size 1 1)
					(thickness 0.15)
				)
			)
		)
		(property "Size" "1.0x0.5"
			(at 0 0 0)
			(layer "F.Fab")
			(hide yes)
			(effects
				(font
					(size 1 1)
					(thickness 0.15)
				)
			)
		)
		(property "Val" "6n2/0.7A"
			(at 0 0 0)
			(layer "F.Fab")
			(hide yes)
			(effects
				(font
					(size 1 1)
					(thickness 0.15)
				)
			)
		)
		(sheetname "/SDI/")
		(sheetfile "sdi.kicad_sch")
		(attr smd)
		(fp_rect
			(start -0.925 -0.47)
			(end 0.925 0.47)
			(stroke
				(width 0.05)
				(type default)
			)
			(fill no)
			(layer "F.CrtYd")
		)
		(fp_rect
			(start -0.499 -0.249)
			(end 0.499 0.249)
			(stroke
				(width 0.15)
				(type solid)
			)
			(fill no)
			(layer "F.Fab")
		)
		(fp_text user "${REFERENCE}"
			(at -0.932 3.168 0)
			(layer "F.Fab")
			(effects
				(font
					(size 0.7 0.7)
					(thickness 0.15)
				)
				(justify left bottom)
			)
		)
		(fp_text user "License: Apache-2.0"
			(at -0.932 5.17 0)
			(layer "F.Fab")
			(effects
				(font
					(size 0.7 0.7)
					(thickness 0.15)
				)
				(justify left bottom)
			)
		)
		(fp_text user "Author: Antmicro"
			(at -0.932 4.17 0)
			(layer "F.Fab")
			(effects
				(font
					(size 0.7 0.7)
					(thickness 0.15)
				)
				(justify left bottom)
			)
		)
		(pad "1" smd roundrect
			(at -0.48 0)
			(size 0.59 0.64)
			(layers "F.Cu" "F.Mask" "F.Paste")
			(roundrect_rratio 0.25)
			(net 251 "/SDI/SDI_OUT_F2")
			(pintype "passive")
		)
		(pad "2" smd roundrect
			(at 0.48 0)
			(size 0.59 0.64)
			(layers "F.Cu" "F.Mask" "F.Paste")
			(roundrect_rratio 0.25)
			(net 254 "/SDI/SDI_OUT_N")
			(pintype "passive")
		)
	)
	(footprint "antmicro-footprints:TP_SMD_0.75mm"
		(layer "F.Cu")
		(at 137.19 104.45 90)
		(property "Reference" "TP5"
			(at 0 -0.6 90)
			(layer "F.SilkS")
			(effects
				(font
					(size 0.65 0.65)
					(thickness 0.15)
				)
				(justify left bottom)
			)
		)
		(property "Value" "TP_0.75mm_SMD"
			(at 0 1.2 90)
			(layer "F.Fab")
			(hide yes)
			(effects
				(font
					(size 0.7 0.7)
					(thickness 0.15)
				)
				(justify left bottom)
			)
		)
		(property "Description" "SMT test point"
			(at 0 0 90)
			(layer "F.Fab")
			(hide yes)
			(effects
				(font
					(size 1.27 1.27)
					(thickness 0.15)
				)
			)
		)
		(property "Author" "Antmicro"
			(at 241.64 -32.74 0)
			(layer "F.Fab")
			(hide yes)
			(effects
				(font
					(size 1 1)
					(thickness 0.15)
				)
			)
		)
		(property "License" "Apache-2.0"
			(at 241.64 -32.74 0)
			(layer "F.Fab")
			(hide yes)
			(effects
				(font
					(size 1 1)
					(thickness 0.15)
				)
			)
		)
		(property "MPN" ""
			(at 241.64 -32.74 0)
			(layer "F.Fab")
			(hide yes)
			(effects
				(font
					(size 1 1)
					(thickness 0.15)
				)
			)
		)
		(property "Manufacturer" ""
			(at 241.64 -32.74 0)
			(layer "F.Fab")
			(hide yes)
			(effects
				(font
					(size 1 1)
					(thickness 0.15)
				)
			)
		)
		(sheetname "/Power Supply/")
		(sheetfile "supply.kicad_sch")
		(attr exclude_from_pos_files)
		(fp_circle
			(center 0 0)
			(end 0.475 0)
			(stroke
				(width 0.05)
				(type default)
			)
			(fill no)
			(layer "F.CrtYd")
		)
		(fp_text user "Author: Antmicro"
			(at -0.4 3.901 90)
			(layer "F.Fab")
			(effects
				(font
					(size 0.7 0.7)
					(thickness 0.15)
				)
				(justify left bottom)
			)
		)
		(fp_text user "${REFERENCE}"
			(at -0.4 2.7 90)
			(layer "F.Fab")
			(effects
				(font
					(size 0.7 0.7)
					(thickness 0.15)
				)
				(justify left bottom)
			)
		)
		(fp_text user "License: Apache-2.0"
			(at -0.4 5.101 90)
			(layer "F.Fab")
			(effects
				(font
					(size 0.7 0.7)
					(thickness 0.15)
				)
				(justify left bottom)
			)
		)
		(pad "1" smd circle
			(at 0 0 90)
			(size 0.75 0.75)
			(layers "F.Cu" "F.Mask")
			(net 49 "1V0_Clean")
			(pinfunction "1")
			(pintype "passive")
		)
	)
	(footprint "antmicro-footprints:C_0402_1005Metric"
		(layer "F.Cu")
		(at 129.33 67.025 -90)
		(descr "Capacitor SMD 0402")
		(tags "capacitor SMD 0402")
		(property "Reference" "C119"
			(at -1.385 -1.4 90)
			(layer "F.SilkS")
			(effects
				(font
					(size 0.65 0.65)
					(thickness 0.15)
				)
				(justify right bottom)
			)
		)
		(property "Value" "C_100n_0402"
			(at 0 1.4 90)
			(layer "F.Fab")
			(hide yes)
			(effects
				(font
					(size 0.7 0.7)
					(thickness 0.15)
				)
				(justify right bottom)
			)
		)
		(property "Datasheet" "https://www.murata.com/products/productdetail?partno=GRM155R61H104KE14%23"
			(at 0 0 270)
			(layer "F.Fab")
			(hide yes)
			(effects
				(font
					(size 1.27 1.27)
					(thickness 0.15)
				)
			)
		)
		(property "Description" "SMD Multilayer Ceramic Capacitor, 0.1 µF, 50 V, 0402 [1005 Metric], ± 10%, X5R, GRM Series"
			(at 0 0 270)
			(layer "F.Fab")
			(hide yes)
			(effects
				(font
					(size 1.27 1.27)
					(thickness 0.15)
				)
			)
		)
		(property "Author" "Antmicro"
			(at 62.305 196.355 0)
			(layer "F.Fab")
			(hide yes)
			(effects
				(font
					(size 1 1)
					(thickness 0.15)
				)
			)
		)
		(property "Dielectric" "X5R"
			(at 62.305 196.355 0)
			(layer "F.Fab")
			(hide yes)
			(effects
				(font
					(size 1 1)
					(thickness 0.15)
				)
			)
		)
		(property "License" "Apache-2.0"
			(at 62.305 196.355 0)
			(layer "F.Fab")
			(hide yes)
			(effects
				(font
					(size 1 1)
					(thickness 0.15)
				)
			)
		)
		(property "MPN" "GRM155R61H104KE14D"
			(at 62.305 196.355 0)
			(layer "F.Fab")
			(hide yes)
			(effects
				(font
					(size 1 1)
					(thickness 0.15)
				)
			)
		)
		(property "Manufacturer" "Murata"
			(at 62.305 196.355 0)
			(layer "F.Fab")
			(hide yes)
			(effects
				(font
					(size 1 1)
					(thickness 0.15)
				)
			)
		)
		(property "Val" "100n"
			(at 62.305 196.355 0)
			(layer "F.Fab")
			(hide yes)
			(effects
				(font
					(size 1 1)
					(thickness 0.15)
				)
			)
		)
		(property "Voltage" "50V"
			(at 62.305 196.355 0)
			(layer "F.Fab")
			(hide yes)
			(effects
				(font
					(size 1 1)
					(thickness 0.15)
				)
			)
		)
		(sheetname "/DDR3/")
		(sheetfile "ddr3.kicad_sch")
		(attr smd)
		(fp_rect
			(start -0.925 -0.47)
			(end 0.925 0.47)
			(stroke
				(width 0.05)
				(type default)
			)
			(fill no)
			(layer "F.CrtYd")
		)
		(fp_line
			(start -0.494 0.248)
			(end -0.494 -0.25)
			(stroke
				(width 0.15)
				(type solid)
			)
			(layer "F.Fab")
		)
		(fp_line
			(start 0.504 0.248)
			(end -0.494 0.248)
			(stroke
				(width 0.15)
				(type solid)
			)
			(layer "F.Fab")
		)
		(fp_line
			(start -0.494 -0.25)
			(end 0.504 -0.25)
			(stroke
				(width 0.15)
				(type solid)
			)
			(layer "F.Fab")
		)
		(fp_line
			(start 0.504 -0.25)
			(end 0.504 0.248)
			(stroke
				(width 0.15)
				(type solid)
			)
			(layer "F.Fab")
		)
		(fp_text user "License: Apache-2.0"
			(at -0.939 5.799 270)
			(layer "F.Fab")
			(effects
				(font
					(size 0.7 0.7)
					(thickness 0.15)
				)
				(justify left bottom)
			)
		)
		(fp_text user "Author: Antmicro"
			(at -0.939 3.399 270)
			(layer "F.Fab")
			(effects
				(font
					(size 0.7 0.7)
					(thickness 0.15)
				)
				(justify left bottom)
			)
		)
		(fp_text user "${REFERENCE}"
			(at -0.939 4.599 270)
			(layer "F.Fab")
			(effects
				(font
					(size 0.7 0.7)
					(thickness 0.15)
				)
				(justify left bottom)
			)
		)
		(pad "1" smd roundrect
			(at -0.48 0 270)
			(size 0.59 0.64)
			(layers "F.Cu" "F.Mask" "F.Paste")
			(roundrect_rratio 0.25)
			(net 5 "Vref")
			(pintype "passive")
		)
		(pad "2" smd roundrect
			(at 0.48 0 270)
			(size 0.59 0.64)
			(layers "F.Cu" "F.Mask" "F.Paste")
			(roundrect_rratio 0.25)
			(net 248 "+1V5")
			(pintype "passive")
		)
	)
	(footprint "antmicro-footprints:C_0402_1005Metric"
		(layer "F.Cu")
		(at 140.13 71.04 90)
		(descr "Capacitor SMD 0402")
		(tags "capacitor SMD 0402")
		(property "Reference" "C9"
			(at -0.8 -0.7 90)
			(layer "F.SilkS")
			(effects
				(font
					(size 0.65 0.65)
					(thickness 0.15)
				)
				(justify left bottom)
			)
		)
		(property "Value" "C_100n_0402"
			(at 0 1.4 90)
			(layer "F.Fab")
			(hide yes)
			(effects
				(font
					(size 0.7 0.7)
					(thickness 0.15)
				)
				(justify left bottom)
			)
		)
		(property "Datasheet" "https://www.murata.com/products/productdetail?partno=GRM155R61H104KE14%23"
			(at 0 0 90)
			(layer "F.Fab")
			(hide yes)
			(effects
				(font
					(size 1.27 1.27)
					(thickness 0.15)
				)
			)
		)
		(property "Description" "SMD Multilayer Ceramic Capacitor, 0.1 µF, 50 V, 0402 [1005 Metric], ± 10%, X5R, GRM Series"
			(at 0 0 90)
			(layer "F.Fab")
			(hide yes)
			(effects
				(font
					(size 1.27 1.27)
					(thickness 0.15)
				)
			)
		)
		(property "Author" "Antmicro"
			(at 211.17 -69.09 0)
			(layer "F.Fab")
			(hide yes)
			(effects
				(font
					(size 1 1)
					(thickness 0.15)
				)
			)
		)
		(property "Dielectric" "X5R"
			(at 211.17 -69.09 0)
			(layer "F.Fab")
			(hide yes)
			(effects
				(font
					(size 1 1)
					(thickness 0.15)
				)
			)
		)
		(property "License" "Apache-2.0"
			(at 211.17 -69.09 0)
			(layer "F.Fab")
			(hide yes)
			(effects
				(font
					(size 1 1)
					(thickness 0.15)
				)
			)
		)
		(property "MPN" "GRM155R61H104KE14D"
			(at 211.17 -69.09 0)
			(layer "F.Fab")
			(hide yes)
			(effects
				(font
					(size 1 1)
					(thickness 0.15)
				)
			)
		)
		(property "Manufacturer" "Murata"
			(at 211.17 -69.09 0)
			(layer "F.Fab")
			(hide yes)
			(effects
				(font
					(size 1 1)
					(thickness 0.15)
				)
			)
		)
		(property "Val" "100n"
			(at 211.17 -69.09 0)
			(layer "F.Fab")
			(hide yes)
			(effects
				(font
					(size 1 1)
					(thickness 0.15)
				)
			)
		)
		(property "Voltage" "50V"
			(at 211.17 -69.09 0)
			(layer "F.Fab")
			(hide yes)
			(effects
				(font
					(size 1 1)
					(thickness 0.15)
				)
			)
		)
		(sheetname "/Power Supply/")
		(sheetfile "supply.kicad_sch")
		(attr smd)
		(fp_rect
			(start -0.925 -0.47)
			(end 0.925 0.47)
			(stroke
				(width 0.05)
				(type default)
			)
			(fill no)
			(layer "F.CrtYd")
		)
		(fp_line
			(start 0.504 -0.25)
			(end 0.504 0.248)
			(stroke
				(width 0.15)
				(type solid)
			)
			(layer "F.Fab")
		)
		(fp_line
			(start -0.494 -0.25)
			(end 0.504 -0.25)
			(stroke
				(width 0.15)
				(type solid)
			)
			(layer "F.Fab")
		)
		(fp_line
			(start 0.504 0.248)
			(end -0.494 0.248)
			(stroke
				(width 0.15)
				(type solid)
			)
			(layer "F.Fab")
		)
		(fp_line
			(start -0.494 0.248)
			(end -0.494 -0.25)
			(stroke
				(width 0.15)
				(type solid)
			)
			(layer "F.Fab")
		)
		(fp_text user "License: Apache-2.0"
			(at -0.939 5.799 90)
			(layer "F.Fab")
			(effects
				(font
					(size 0.7 0.7)
					(thickness 0.15)
				)
				(justify left bottom)
			)
		)
		(fp_text user "${REFERENCE}"
			(at -0.939 4.599 90)
			(layer "F.Fab")
			(effects
				(font
					(size 0.7 0.7)
					(thickness 0.15)
				)
				(justify left bottom)
			)
		)
		(fp_text user "Author: Antmicro"
			(at -0.939 3.399 90)
			(layer "F.Fab")
			(effects
				(font
					(size 0.7 0.7)
					(thickness 0.15)
				)
				(justify left bottom)
			)
		)
		(pad "1" smd roundrect
			(at -0.48 0 90)
			(size 0.59 0.64)
			(layers "F.Cu" "F.Mask" "F.Paste")
			(roundrect_rratio 0.25)
			(net 276 "/Power Supply/1V0_SW")
			(pintype "passive")
		)
		(pad "2" smd roundrect
			(at 0.48 0 90)
			(size 0.59 0.64)
			(layers "F.Cu" "F.Mask" "F.Paste")
			(roundrect_rratio 0.25)
			(net 61 "Net-(U5-BST)")
			(pintype "passive")
		)
	)
	(footprint "antmicro-footprints:R_0402_1005Metric"
		(layer "F.Cu")
		(at 156.69 65.1 -90)
		(descr "Resistor SMD 0402")
		(tags "resistor SMD 0402")
		(property "Reference" "R9"
			(at 2.34 -0.34 270)
			(layer "F.SilkS")
			(effects
				(font
					(size 0.65 0.65)
					(thickness 0.15)
				)
				(justify left bottom)
			)
		)
		(property "Value" "R_10k_0402"
			(at 0 1.4 270)
			(layer "F.Fab")
			(hide yes)
			(effects
				(font
					(size 0.7 0.7)
					(thickness 0.15)
				)
				(justify left bottom)
			)
		)
		(property "Datasheet" "https://www.bourns.com/docs/product-datasheets/cr.pdf"
			(at 0 0 270)
			(layer "F.Fab")
			(hide yes)
			(effects
				(font
					(size 1.27 1.27)
					(thickness 0.15)
				)
			)
		)
		(property "Description" "SMD Chip Resistor, 10 kohm, ± 1%, 62.5 mW, 0402 [1005 Metric], Thick Film, General Purpose"
			(at 0 0 270)
			(layer "F.Fab")
			(hide yes)
			(effects
				(font
					(size 1.27 1.27)
					(thickness 0.15)
				)
			)
		)
		(property "Author" "Antmicro"
			(at 91.59 221.79 0)
			(layer "F.Fab")
			(hide yes)
			(effects
				(font
					(size 1 1)
					(thickness 0.15)
				)
			)
		)
		(property "License" "Apache-2.0"
			(at 91.59 221.79 0)
			(layer "F.Fab")
			(hide yes)
			(effects
				(font
					(size 1 1)
					(thickness 0.15)
				)
			)
		)
		(property "MPN" "CR0402-FX-1002GLF"
			(at 91.59 221.79 0)
			(layer "F.Fab")
			(hide yes)
			(effects
				(font
					(size 1 1)
					(thickness 0.15)
				)
			)
		)
		(property "Manufacturer" "Bourns"
			(at 91.59 221.79 0)
			(layer "F.Fab")
			(hide yes)
			(effects
				(font
					(size 1 1)
					(thickness 0.15)
				)
			)
		)
		(property "Tolerance" "1%"
			(at 91.59 221.79 0)
			(layer "F.Fab")
			(hide yes)
			(effects
				(font
					(size 1 1)
					(thickness 0.15)
				)
			)
		)
		(property "Val" "10k"
			(at 91.59 221.79 0)
			(layer "F.Fab")
			(hide yes)
			(effects
				(font
					(size 1 1)
					(thickness 0.15)
				)
			)
		)
		(sheetname "/Power Supply/")
		(sheetfile "supply.kicad_sch")
		(attr smd)
		(fp_rect
			(start -0.925 -0.47)
			(end 0.925 0.47)
			(stroke
				(width 0.05)
				(type default)
			)
			(fill no)
			(layer "F.CrtYd")
		)
		(fp_rect
			(start -0.5 -0.25)
			(end 0.5 0.25)
			(stroke
				(width 0.15)
				(type solid)
			)
			(fill no)
			(layer "F.Fab")
		)
		(fp_text user "Author: Antmicro"
			(at -0.95 4.169 270)
			(layer "F.Fab")
			(effects
				(font
					(size 0.7 0.7)
					(thickness 0.15)
				)
				(justify left bottom)
			)
		)
		(fp_text user "${REFERENCE}"
			(at -0.95 3.168 270)
			(layer "F.Fab")
			(effects
				(font
					(size 0.7 0.7)
					(thickness 0.15)
				)
				(justify left bottom)
			)
		)
		(fp_text user "License: Apache-2.0"
			(at -0.95 5.169 270)
			(layer "F.Fab")
			(effects
				(font
					(size 0.7 0.7)
					(thickness 0.15)
				)
				(justify left bottom)
			)
		)
		(pad "1" smd roundrect
			(at -0.48 0 270)
			(size 0.59 0.64)
			(layers "F.Cu" "F.Mask" "F.Paste")
			(roundrect_rratio 0.25)
			(net 1 "GND")
			(pintype "passive")
		)
		(pad "2" smd roundrect
			(at 0.48 0 270)
			(size 0.59 0.64)
			(layers "F.Cu" "F.Mask" "F.Paste")
			(roundrect_rratio 0.25)
			(net 325 "USB_POWER_IN")
			(pintype "passive")
		)
	)
)
